# T6G (Grand Teton) — schematic netlist excerpt (pin names and nets, part order shuffled) for the footprints in the layout excerpt that follows; sources: Cadence DE-HDL packaged netlist, KiCad conversion of 04192023_DAF0TMB3IC0_F0TG_MB_C_brd_V02_OCP.brd

PR291  Q_RES  1.5 1% EMPTY  pkg 0402LF  page 206 : A = SW_PVDDIO_P0_SW4_RC ; B = GND
R3392  Q_RES  49.9 1% CHIP  pkg 0402LF  page 128 : A = GPU_BASE_STBY_EN_BUF_R ; B = GPU_BASE_STBY_EN_BUF

(kicad_pcb
	(version 20260206)
	(generator "pcbnew")
	(generator_version "10.0")
	(general
		(thickness 1.6)
		(legacy_teardrops no)
	)
	(paper "A4")
	(title_block
		(title "04192023_DAF0TMB3IC0_F0TG_MB_C_brd_V02_OCP.brd")
		(comment 1 "Grand Teton / footprints 4710-4711 of 8354")
	)
	(layers
		(0 "F.Cu" signal "TOP")
		(4 "In1.Cu" signal "GND")
		(6 "In2.Cu" signal "IN1")
		(8 "In3.Cu" signal "GND1")
		(10 "In4.Cu" signal "IN2")
		(12 "In5.Cu" signal "GND2")
		(14 "In6.Cu" signal "IN3")
		(16 "In7.Cu" signal "GND3")
		(18 "In8.Cu" signal "VCC")
		(20 "In9.Cu" signal "VCC1")
		(22 "In10.Cu" signal "GND4")
		(24 "In11.Cu" signal "IN4")
		(26 "In12.Cu" signal "GND5")
		(28 "In13.Cu" signal "IN5")
		(30 "In14.Cu" signal "GND6")
		(32 "In15.Cu" signal "IN6")
		(34 "In16.Cu" signal "GND7")
		(2 "B.Cu" signal "BOTTOM")
		(9 "F.Adhes" user "F.Adhesive")
		(11 "B.Adhes" user "B.Adhesive")
		(13 "F.Paste" user "Package Geometry/Pastemask Top")
		(15 "B.Paste" user "Package Geometry/Pastemask Bottom")
		(5 "F.SilkS" user "Ref Des/Silkscreen Top")
		(7 "B.SilkS" user "Ref Des/Silkscreen Bottom")
		(1 "F.Mask" user "Board Geometry/Soldermask Top")
		(3 "B.Mask" user "Board Geometry/Soldermask Bottom")
		(17 "Dwgs.User" user "User.Drawings")
		(19 "Cmts.User" user "User.Comments")
		(21 "Eco1.User" user "User.Eco1")
		(23 "Eco2.User" user "User.Eco2")
		(25 "Edge.Cuts" user "Board Geometry/Outline")
		(27 "Margin" user)
		(31 "F.CrtYd" user "Package Geometry/Place Bound Top")
		(29 "B.CrtYd" user "Package Geometry/Place Bound Bottom")
		(35 "F.Fab" user "Ref Des/Assembly Top")
		(33 "B.Fab" user "Ref Des/Assembly Bottom")
	)
	(footprint ""
		(layer "F.Cu")
		(at 118.491 -423.672)
		(property "Reference" "R3392"
			(at 0 0 0)
			(layer "F.SilkS")
			(hide yes)
			(effects
				(font
					(size 1.27 1.27)
				)
			)
		)
		(property "Value" ""
			(at 0 0 0)
			(layer "F.Fab")
			(effects
				(font
					(size 1.27 1.27)
				)
			)
		)
		(duplicate_pad_numbers_are_jumpers no)
		(fp_line
			(start -0.7874 -0.4064)
			(end 0.7874 -0.4064)
			(stroke
				(width 0.1524)
				(type default)
			)
			(layer "F.SilkS")
		)
		(fp_line
			(start -0.7874 0.4064)
			(end -0.7874 -0.4064)
			(stroke
				(width 0.1524)
				(type default)
			)
			(layer "F.SilkS")
		)
		(fp_line
			(start 0.7874 -0.4064)
			(end 0.7874 0.4064)
			(stroke
				(width 0.1524)
				(type default)
			)
			(layer "F.SilkS")
		)
		(fp_line
			(start 0.7874 0.4064)
			(end -0.7874 0.4064)
			(stroke
				(width 0.1524)
				(type default)
			)
			(layer "F.SilkS")
		)
		(fp_line
			(start -0.67945 -0.305054)
			(end -0.12065 -0.305054)
			(stroke
				(width 0.1)
				(type default)
			)
			(layer "F.Fab")
		)
		(fp_line
			(start -0.67945 0.3048)
			(end -0.67945 -0.305054)
			(stroke
				(width 0.1)
				(type default)
			)
			(layer "F.Fab")
		)
		(fp_line
			(start -0.12065 -0.305054)
			(end -0.12065 -0.2794)
			(stroke
				(width 0.1)
				(type default)
			)
			(layer "F.Fab")
		)
		(fp_line
			(start -0.12065 -0.2794)
			(end 0.12065 -0.2794)
			(stroke
				(width 0.1)
				(type default)
			)
			(layer "F.Fab")
		)
		(fp_line
			(start -0.12065 0.2794)
			(end -0.12065 0.3048)
			(stroke
				(width 0.1)
				(type default)
			)
			(layer "F.Fab")
		)
		(fp_line
			(start -0.12065 0.3048)
			(end -0.67945 0.3048)
			(stroke
				(width 0.1)
				(type default)
			)
			(layer "F.Fab")
		)
		(fp_line
			(start 0.120396 0.2794)
			(end -0.12065 0.2794)
			(stroke
				(width 0.1)
				(type default)
			)
			(layer "F.Fab")
		)
		(fp_line
			(start 0.120396 0.3048)
			(end 0.120396 0.2794)
			(stroke
				(width 0.1)
				(type default)
			)
			(layer "F.Fab")
		)
		(fp_line
			(start 0.12065 -0.3048)
			(end 0.67945 -0.3048)
			(stroke
				(width 0.1)
				(type default)
			)
			(layer "F.Fab")
		)
		(fp_line
			(start 0.12065 -0.2794)
			(end 0.12065 -0.3048)
			(stroke
				(width 0.1)
				(type default)
			)
			(layer "F.Fab")
		)
		(fp_line
			(start 0.67945 -0.3048)
			(end 0.67945 0.3048)
			(stroke
				(width 0.1)
				(type default)
			)
			(layer "F.Fab")
		)
		(fp_line
			(start 0.67945 0.3048)
			(end 0.120396 0.3048)
			(stroke
				(width 0.1)
				(type default)
			)
			(layer "F.Fab")
		)
		(pad "1" smd circle
			(at -0.40005 0)
			(size 0 0)
			(layers "F.Cu" "F.Mask" "F.Paste")
			(net "GPU_BASE_STBY_EN_BUF_R")
		)
		(pad "2" smd circle
			(at 0.40005 0)
			(size 0 0)
			(layers "F.Cu" "F.Mask" "F.Paste")
			(net "GPU_BASE_STBY_EN_BUF")
		)
	)
	(footprint ""
		(layer "F.Cu")
		(at 271.744948 -344.982038 90)
		(property "Reference" "PR291"
			(at 0 0 90)
			(layer "F.SilkS")
			(hide yes)
			(effects
				(font
					(size 1.27 1.27)
				)
			)
		)
		(property "Value" ""
			(at 0 0 90)
			(layer "F.Fab")
			(effects
				(font
					(size 1.27 1.27)
				)
			)
		)
		(duplicate_pad_numbers_are_jumpers no)
		(fp_line
			(start 0.7874 -0.4064)
			(end 0.7874 0.4064)
			(stroke
				(width 0.1524)
				(type default)
			)
			(layer "F.SilkS")
		)
		(fp_line
			(start -0.7874 -0.4064)
			(end 0.7874 -0.4064)
			(stroke
				(width 0.1524)
				(type default)
			)
			(layer "F.SilkS")
		)
		(fp_line
			(start 0.7874 0.4064)
			(end -0.7874 0.4064)
			(stroke
				(width 0.1524)
				(type default)
			)
			(layer "F.SilkS")
		)
		(fp_line
			(start -0.7874 0.4064)
			(end -0.7874 -0.4064)
			(stroke
				(width 0.1524)
				(type default)
			)
			(layer "F.SilkS")
		)
		(fp_line
			(start -0.12065 -0.305054)
			(end -0.12065 -0.2794)
			(stroke
				(width 0.1)
				(type default)
			)
			(layer "F.Fab")
		)
		(fp_line
			(start -0.67945 -0.305054)
			(end -0.12065 -0.305054)
			(stroke
				(width 0.1)
				(type default)
			)
			(layer "F.Fab")
		)
		(fp_line
			(start 0.67945 -0.3048)
			(end 0.67945 0.3048)
			(stroke
				(width 0.1)
				(type default)
			)
			(layer "F.Fab")
		)
		(fp_line
			(start 0.12065 -0.3048)
			(end 0.67945 -0.3048)
			(stroke
				(width 0.1)
				(type default)
			)
			(layer "F.Fab")
		)
		(fp_line
			(start 0.12065 -0.2794)
			(end 0.12065 -0.3048)
			(stroke
				(width 0.1)
				(type default)
			)
			(layer "F.Fab")
		)
		(fp_line
			(start -0.12065 -0.2794)
			(end 0.12065 -0.2794)
			(stroke
				(width 0.1)
				(type default)
			)
			(layer "F.Fab")
		)
		(fp_line
			(start 0.120396 0.2794)
			(end -0.12065 0.2794)
			(stroke
				(width 0.1)
				(type default)
			)
			(layer "F.Fab")
		)
		(fp_line
			(start -0.12065 0.2794)
			(end -0.12065 0.3048)
			(stroke
				(width 0.1)
				(type default)
			)
			(layer "F.Fab")
		)
		(fp_line
			(start 0.67945 0.3048)
			(end 0.120396 0.3048)
			(stroke
				(width 0.1)
				(type default)
			)
			(layer "F.Fab")
		)
		(fp_line
			(start 0.120396 0.3048)
			(end 0.120396 0.2794)
			(stroke
				(width 0.1)
				(type default)
			)
			(layer "F.Fab")
		)
		(fp_line
			(start -0.12065 0.3048)
			(end -0.67945 0.3048)
			(stroke
				(width 0.1)
				(type default)
			)
			(layer "F.Fab")
		)
		(fp_line
			(start -0.67945 0.3048)
			(end -0.67945 -0.305054)
			(stroke
				(width 0.1)
				(type default)
			)
			(layer "F.Fab")
		)
		(pad "1" smd circle
			(at -0.40005 0 90)
			(size 0 0)
			(layers "F.Cu" "F.Mask" "F.Paste")
			(net "SW_PVDDIO_P0_SW4_RC")
		)
		(pad "2" smd circle
			(at 0.40005 0 90)
			(size 0 0)
			(layers "F.Cu" "F.Mask" "F.Paste")
			(net "GND")
		)
	)
)
